(kicad_pcb
	(version 20260206)
	(generator "pcbnew")
	(generator_version "10.0")
	(general
		(thickness 1.6)
		(legacy_teardrops no)
	)
	(paper "A4")
	(title_block
		(title "baseboard — 13948-1b.1110WZS1818.brd")
		(comment 1 "Honey Badger (Wiwynn) / footprints 2376-2383 of 2523")
	)
	(layers
		(0 "F.Cu" signal "TOP")
		(4 "In1.Cu" signal "L2GND")
		(6 "In2.Cu" signal "L3")
		(8 "In3.Cu" signal "L4VCC")
		(10 "In4.Cu" signal "L5VCC")
		(12 "In5.Cu" signal "L6")
		(14 "In6.Cu" signal "L7GND")
		(2 "B.Cu" signal "BOTTOM")
		(9 "F.Adhes" user "F.Adhesive")
		(11 "B.Adhes" user "B.Adhesive")
		(13 "F.Paste" user "Package Geometry/Pastemask Top")
		(15 "B.Paste" user "Package Geometry/Pastemask Bottom")
		(5 "F.SilkS" user "Ref Des/Silkscreen Top")
		(7 "B.SilkS" user "Ref Des/Silkscreen Bottom")
		(1 "F.Mask" user "Board Geometry/Soldermask Top")
		(3 "B.Mask" user "Board Geometry/Soldermask Bottom")
		(17 "Dwgs.User" user "User.Drawings")
		(19 "Cmts.User" user "User.Comments")
		(21 "Eco1.User" user "User.Eco1")
		(23 "Eco2.User" user "User.Eco2")
		(25 "Edge.Cuts" user "Board Geometry/Outline")
		(27 "Margin" user)
		(31 "F.CrtYd" user "Package Geometry/Place Bound Top")
		(29 "B.CrtYd" user "Package Geometry/Place Bound Bottom")
		(35 "F.Fab" user "Ref Des/Assembly Top")
		(33 "B.Fab" user "Ref Des/Assembly Bottom")
	)
	(footprint ""
		(layer "B.Cu")
		(at 93.99016 -31.623)
		(property "Reference" "SC862"
			(at 0 0 0)
			(layer "B.SilkS")
			(hide yes)
			(effects
				(font
					(size 1.27 1.27)
				)
				(justify mirror)
			)
		)
		(property "Value" "SCD22U6D3V1MX-1-GP"
			(at 2.8321 -1.7399 0)
			(unlocked yes)
			(layer "B.Fab")
			(hide yes)
			(effects
				(font
					(size 1.016 1.016)
					(thickness 0.1524)
				)
				(justify mirror)
			)
		)
		(property "Device Type" "C0201H13"
			(at 2.8321 -3.2639 0)
			(unlocked yes)
			(layer "B.Fab")
			(hide yes)
			(effects
				(font
					(size 1.016 1.016)
					(thickness 0.1524)
				)
				(justify mirror)
			)
		)
		(duplicate_pad_numbers_are_jumpers no)
		(fp_rect
			(start 0.2794 0.6477)
			(end -0.2794 -0.6477)
			(stroke
				(width 0)
				(type default)
			)
			(fill no)
			(layer "B.CrtYd")
		)
		(fp_rect
			(start 0.2794 0.6477)
			(end -0.2794 -0.6477)
			(stroke
				(width 0)
				(type default)
			)
			(fill no)
			(layer "B.Fab")
		)
		(pad "1" smd custom
			(at 0 -0.2794 180)
			(size 0.0762 0.0762)
			(layers "B.Cu" "B.Mask" "B.Paste")
			(net "PCIE_SAS_C_CPU_RX_N0")
			(options
				(clearance outline)
				(anchor circle)
			)
			(primitives
				(gr_poly
					(pts
						(arc
							(start 0.1524 0.127)
							(mid 0.137521 0.162921)
							(end 0.1016 0.1778)
						)
						(arc
							(start -0.1016 0.1778)
							(mid -0.137521 0.162921)
							(end -0.1524 0.127)
						)
						(arc
							(start -0.1524 -0.127)
							(mid -0.137521 -0.162921)
							(end -0.1016 -0.1778)
						)
						(arc
							(start 0.1016 -0.1778)
							(mid 0.137521 -0.162921)
							(end 0.1524 -0.127)
						)
					)
					(width 0)
					(fill yes)
				)
			)
		)
		(pad "2" smd custom
			(at 0 0.2794 180)
			(size 0.0762 0.0762)
			(layers "B.Cu" "B.Mask" "B.Paste")
			(net "PCIE_SAS_CPU_RX_N0")
			(options
				(clearance outline)
				(anchor circle)
			)
			(primitives
				(gr_poly
					(pts
						(arc
							(start 0.1524 0.127)
							(mid 0.137521 0.162921)
							(end 0.1016 0.1778)
						)
						(arc
							(start -0.1016 0.1778)
							(mid -0.137521 0.162921)
							(end -0.1524 0.127)
						)
						(arc
							(start -0.1524 -0.127)
							(mid -0.137521 -0.162921)
							(end -0.1016 -0.1778)
						)
						(arc
							(start 0.1016 -0.1778)
							(mid 0.137521 -0.162921)
							(end 0.1524 -0.127)
						)
					)
					(width 0)
					(fill yes)
				)
			)
		)
	)
	(footprint ""
		(layer "B.Cu")
		(at 84.836 -20.955)
		(property "Reference" "PC222"
			(at 0 0 0)
			(layer "B.SilkS")
			(hide yes)
			(effects
				(font
					(size 1.27 1.27)
				)
				(justify mirror)
			)
		)
		(property "Value" "SCD33U6D3V2KX-1-GP"
			(at -1.1811 -2.7051 0)
			(unlocked yes)
			(layer "B.Fab")
			(hide yes)
			(effects
				(font
					(size 1.016 1.016)
					(thickness 0.1524)
				)
				(justify mirror)
			)
		)
		(property "Device Type" "C402H22"
			(at -1.1811 -4.2291 0)
			(unlocked yes)
			(layer "B.Fab")
			(hide yes)
			(effects
				(font
					(size 1.016 1.016)
					(thickness 0.1524)
				)
				(justify mirror)
			)
		)
		(duplicate_pad_numbers_are_jumpers no)
		(fp_rect
			(start 0.4318 0.9525)
			(end -0.4318 -0.9525)
			(stroke
				(width 0)
				(type default)
			)
			(fill no)
			(layer "B.CrtYd")
		)
		(fp_rect
			(start 0.4318 0.9525)
			(end -0.4318 -0.9525)
			(stroke
				(width 0)
				(type default)
			)
			(fill no)
			(layer "B.Fab")
		)
		(pad "1" smd custom
			(at 0 -0.4445 180)
			(size 0.1524 0.1524)
			(layers "B.Cu" "B.Mask" "B.Paste")
			(net "AVSO_VREF")
			(options
				(clearance outline)
				(anchor circle)
			)
			(primitives
				(gr_poly
					(pts
						(arc
							(start 0.3048 0.2032)
							(mid 0.275042 0.275042)
							(end 0.2032 0.3048)
						)
						(arc
							(start -0.2032 0.3048)
							(mid -0.275042 0.275042)
							(end -0.3048 0.2032)
						)
						(arc
							(start -0.3048 -0.2032)
							(mid -0.275042 -0.275042)
							(end -0.2032 -0.3048)
						)
						(arc
							(start 0.2032 -0.3048)
							(mid 0.275042 -0.275042)
							(end 0.3048 -0.2032)
						)
					)
					(width 0)
					(fill yes)
				)
			)
		)
		(pad "2" smd custom
			(at 0 0.4445 180)
			(size 0.1524 0.1524)
			(layers "B.Cu" "B.Mask" "B.Paste")
			(net "GND")
			(options
				(clearance outline)
				(anchor circle)
			)
			(primitives
				(gr_poly
					(pts
						(arc
							(start 0.3048 0.2032)
							(mid 0.275042 0.275042)
							(end 0.2032 0.3048)
						)
						(arc
							(start -0.2032 0.3048)
							(mid -0.275042 0.275042)
							(end -0.3048 0.2032)
						)
						(arc
							(start -0.3048 -0.2032)
							(mid -0.275042 -0.275042)
							(end -0.2032 -0.3048)
						)
						(arc
							(start 0.2032 -0.3048)
							(mid 0.275042 -0.275042)
							(end 0.3048 -0.2032)
						)
					)
					(width 0)
					(fill yes)
				)
			)
		)
	)
	(footprint ""
		(layer "B.Cu")
		(at 117.710966 -35.306)
		(property "Reference" "STP11"
			(at 0 0 0)
			(layer "B.SilkS")
			(hide yes)
			(effects
				(font
					(size 1.27 1.27)
				)
				(justify mirror)
			)
		)
		(property "Value" "TPAD28"
			(at -0.0127 -1.8034 0)
			(unlocked yes)
			(layer "B.Fab")
			(hide yes)
			(effects
				(font
					(size 1.016 1.016)
					(thickness 0.1524)
				)
				(justify mirror)
			)
		)
		(property "Device Type" "TPAD28"
			(at -0.0127 -3.3274 0)
			(unlocked yes)
			(layer "B.Fab")
			(hide yes)
			(effects
				(font
					(size 1.016 1.016)
					(thickness 0.1524)
				)
				(justify mirror)
			)
		)
		(duplicate_pad_numbers_are_jumpers no)
		(fp_poly
			(pts
				(arc
					(start 0.3556 0)
					(mid -0.3556 0)
					(end 0.3556 0)
				)
			)
			(stroke
				(width 0)
				(type default)
			)
			(fill no)
			(layer "B.CrtYd")
		)
		(fp_poly
			(pts
				(arc
					(start 0.6096 0)
					(mid -0.6096 0)
					(end 0.6096 0)
				)
			)
			(stroke
				(width 0)
				(type default)
			)
			(fill no)
			(layer "B.Fab")
		)
		(pad "1" smd circle
			(at 0 0 180)
			(size 0.7112 0.7112)
			(layers "B.Cu" "B.Mask" "B.Paste")
			(net "IOC_GPIO_30")
		)
	)
	(footprint ""
		(layer "B.Cu")
		(at 296.164 -164.211 180)
		(property "Reference" "R282"
			(at 0 0 0)
			(layer "B.SilkS")
			(hide yes)
			(effects
				(font
					(size 1.27 1.27)
				)
				(justify mirror)
			)
		)
		(property "Value" "0R2J-2-GP"
			(at -0.064008 -3.993896 180)
			(unlocked yes)
			(layer "B.Fab")
			(hide yes)
			(effects
				(font
					(size 1.016 1.016)
					(thickness 0.1524)
				)
				(justify mirror)
			)
		)
		(property "Device Type" "R402H16"
			(at -0.064008 -5.517896 180)
			(unlocked yes)
			(layer "B.Fab")
			(hide yes)
			(effects
				(font
					(size 1.016 1.016)
					(thickness 0.1524)
				)
				(justify mirror)
			)
		)
		(duplicate_pad_numbers_are_jumpers no)
		(fp_line
			(start 0.508 -0.9398)
			(end 0.508 0.9398)
			(stroke
				(width 0.1524)
				(type default)
			)
			(layer "B.SilkS")
		)
		(fp_line
			(start -0.508 -0.9398)
			(end 0.508 -0.9398)
			(stroke
				(width 0.1524)
				(type default)
			)
			(layer "B.SilkS")
		)
		(fp_rect
			(start 0.508 0.9398)
			(end -0.508 -0.9398)
			(stroke
				(width 0)
				(type default)
			)
			(fill no)
			(layer "B.CrtYd")
		)
		(fp_rect
			(start 0.508 0.9398)
			(end -0.508 -0.9398)
			(stroke
				(width 0)
				(type default)
			)
			(fill no)
			(layer "B.Fab")
		)
		(pad "1" smd custom
			(at 0 -0.4445)
			(size 0.1397 0.1397)
			(layers "B.Cu" "B.Mask" "B.Paste")
			(net "RMII_PHY_BMC_RXD0")
			(options
				(clearance outline)
				(anchor circle)
			)
			(primitives
				(gr_poly
					(pts
						(arc
							(start -0.1778 0.2794)
							(mid -0.249642 0.249642)
							(end -0.2794 0.1778)
						)
						(arc
							(start -0.2794 -0.1778)
							(mid -0.249642 -0.249642)
							(end -0.1778 -0.2794)
						)
						(arc
							(start 0.1778 -0.2794)
							(mid 0.249642 -0.249642)
							(end 0.2794 -0.1778)
						)
						(arc
							(start 0.2794 0.1778)
							(mid 0.249642 0.249642)
							(end 0.1778 0.2794)
						)
					)
					(width 0)
					(fill yes)
				)
			)
		)
		(pad "2" smd custom
			(at 0 0.4445)
			(size 0.1397 0.1397)
			(layers "B.Cu" "B.Mask" "B.Paste")
			(net "RMII0_PHY_BMC_C_RXD0")
			(options
				(clearance outline)
				(anchor circle)
			)
			(primitives
				(gr_poly
					(pts
						(arc
							(start -0.1778 0.2794)
							(mid -0.249642 0.249642)
							(end -0.2794 0.1778)
						)
						(arc
							(start -0.2794 -0.1778)
							(mid -0.249642 -0.249642)
							(end -0.1778 -0.2794)
						)
						(arc
							(start 0.1778 -0.2794)
							(mid 0.249642 -0.249642)
							(end 0.2794 -0.1778)
						)
						(arc
							(start 0.2794 0.1778)
							(mid 0.249642 0.249642)
							(end 0.1778 0.2794)
						)
					)
					(width 0)
					(fill yes)
				)
			)
		)
	)
	(footprint ""
		(layer "B.Cu")
		(at 103.994966 -40.386)
		(property "Reference" "SC1056"
			(at 0 0 0)
			(layer "B.SilkS")
			(hide yes)
			(effects
				(font
					(size 1.27 1.27)
				)
				(justify mirror)
			)
		)
		(property "Value" "SCD1U16V2KX-3GP"
			(at -1.1811 -2.7051 0)
			(unlocked yes)
			(layer "B.Fab")
			(hide yes)
			(effects
				(font
					(size 1.016 1.016)
					(thickness 0.1524)
				)
				(justify mirror)
			)
		)
		(property "Device Type" "C402H22"
			(at -1.1811 -4.2291 0)
			(unlocked yes)
			(layer "B.Fab")
			(hide yes)
			(effects
				(font
					(size 1.016 1.016)
					(thickness 0.1524)
				)
				(justify mirror)
			)
		)
		(duplicate_pad_numbers_are_jumpers no)
		(fp_rect
			(start 0.4318 0.9525)
			(end -0.4318 -0.9525)
			(stroke
				(width 0)
				(type default)
			)
			(fill no)
			(layer "B.CrtYd")
		)
		(fp_rect
			(start 0.4318 0.9525)
			(end -0.4318 -0.9525)
			(stroke
				(width 0)
				(type default)
			)
			(fill no)
			(layer "B.Fab")
		)
		(pad "1" smd custom
			(at 0 -0.4445 180)
			(size 0.1524 0.1524)
			(layers "B.Cu" "B.Mask" "B.Paste")
			(net "P0V955_C")
			(options
				(clearance outline)
				(anchor circle)
			)
			(primitives
				(gr_poly
					(pts
						(arc
							(start 0.3048 0.2032)
							(mid 0.275042 0.275042)
							(end 0.2032 0.3048)
						)
						(arc
							(start -0.2032 0.3048)
							(mid -0.275042 0.275042)
							(end -0.3048 0.2032)
						)
						(arc
							(start -0.3048 -0.2032)
							(mid -0.275042 -0.275042)
							(end -0.2032 -0.3048)
						)
						(arc
							(start 0.2032 -0.3048)
							(mid 0.275042 -0.275042)
							(end 0.3048 -0.2032)
						)
					)
					(width 0)
					(fill yes)
				)
			)
		)
		(pad "2" smd custom
			(at 0 0.4445 180)
			(size 0.1524 0.1524)
			(layers "B.Cu" "B.Mask" "B.Paste")
			(net "GND")
			(options
				(clearance outline)
				(anchor circle)
			)
			(primitives
				(gr_poly
					(pts
						(arc
							(start 0.3048 0.2032)
							(mid 0.275042 0.275042)
							(end 0.2032 0.3048)
						)
						(arc
							(start -0.2032 0.3048)
							(mid -0.275042 0.275042)
							(end -0.3048 0.2032)
						)
						(arc
							(start -0.3048 -0.2032)
							(mid -0.275042 -0.275042)
							(end -0.2032 -0.3048)
						)
						(arc
							(start 0.2032 -0.3048)
							(mid 0.275042 -0.275042)
							(end 0.3048 -0.2032)
						)
					)
					(width 0)
					(fill yes)
				)
			)
		)
	)
	(footprint ""
		(layer "B.Cu")
		(at 120.28297 -104.14 -90)
		(property "Reference" "SC1179"
			(at 0 0 90)
			(layer "B.SilkS")
			(hide yes)
			(effects
				(font
					(size 1.27 1.27)
				)
				(justify mirror)
			)
		)
		(property "Value" "SCD1U6D3V1KX-GP"
			(at 2.8321 -1.7399 270)
			(unlocked yes)
			(layer "B.Fab")
			(hide yes)
			(effects
				(font
					(size 1.016 1.016)
					(thickness 0.1524)
				)
				(justify mirror)
			)
		)
		(property "Device Type" "C0201H13"
			(at 2.8321 -3.2639 270)
			(unlocked yes)
			(layer "B.Fab")
			(hide yes)
			(effects
				(font
					(size 1.016 1.016)
					(thickness 0.1524)
				)
				(justify mirror)
			)
		)
		(duplicate_pad_numbers_are_jumpers no)
		(fp_rect
			(start 0.2794 0.6477)
			(end -0.2794 -0.6477)
			(stroke
				(width 0)
				(type default)
			)
			(fill no)
			(layer "B.CrtYd")
		)
		(fp_rect
			(start 0.2794 0.6477)
			(end -0.2794 -0.6477)
			(stroke
				(width 0)
				(type default)
			)
			(fill no)
			(layer "B.Fab")
		)
		(pad "1" smd custom
			(at 0 -0.2794 90)
			(size 0.0762 0.0762)
			(layers "B.Cu" "B.Mask" "B.Paste")
			(net "GB_VDDA")
			(options
				(clearance outline)
				(anchor circle)
			)
			(primitives
				(gr_poly
					(pts
						(arc
							(start 0.1524 0.127)
							(mid 0.137521 0.162921)
							(end 0.1016 0.1778)
						)
						(arc
							(start -0.1016 0.1778)
							(mid -0.137521 0.162921)
							(end -0.1524 0.127)
						)
						(arc
							(start -0.1524 -0.127)
							(mid -0.137521 -0.162921)
							(end -0.1016 -0.1778)
						)
						(arc
							(start 0.1016 -0.1778)
							(mid 0.137521 -0.162921)
							(end 0.1524 -0.127)
						)
					)
					(width 0)
					(fill yes)
				)
			)
		)
		(pad "2" smd custom
			(at 0 0.2794 90)
			(size 0.0762 0.0762)
			(layers "B.Cu" "B.Mask" "B.Paste")
			(net "GND")
			(options
				(clearance outline)
				(anchor circle)
			)
			(primitives
				(gr_poly
					(pts
						(arc
							(start 0.1524 0.127)
							(mid 0.137521 0.162921)
							(end 0.1016 0.1778)
						)
						(arc
							(start -0.1016 0.1778)
							(mid -0.137521 0.162921)
							(end -0.1524 0.127)
						)
						(arc
							(start -0.1524 -0.127)
							(mid -0.137521 -0.162921)
							(end -0.1016 -0.1778)
						)
						(arc
							(start 0.1016 -0.1778)
							(mid 0.137521 -0.162921)
							(end 0.1524 -0.127)
						)
					)
					(width 0)
					(fill yes)
				)
			)
		)
	)
	(footprint ""
		(layer "B.Cu")
		(at 102.997 -227.965 -90)
		(property "Reference" "R663"
			(at 0 0 90)
			(layer "B.SilkS")
			(hide yes)
			(effects
				(font
					(size 1.27 1.27)
				)
				(justify mirror)
			)
		)
		(property "Value" "0R2J-2-GP"
			(at -0.064008 -3.993896 270)
			(unlocked yes)
			(layer "B.Fab")
			(hide yes)
			(effects
				(font
					(size 1.016 1.016)
					(thickness 0.1524)
				)
				(justify mirror)
			)
		)
		(property "Device Type" "R402H16"
			(at -0.064008 -5.517896 270)
			(unlocked yes)
			(layer "B.Fab")
			(hide yes)
			(effects
				(font
					(size 1.016 1.016)
					(thickness 0.1524)
				)
				(justify mirror)
			)
		)
		(duplicate_pad_numbers_are_jumpers no)
		(fp_line
			(start -0.508 -0.9398)
			(end 0.508 -0.9398)
			(stroke
				(width 0.1524)
				(type default)
			)
			(layer "B.SilkS")
		)
		(fp_line
			(start 0.508 -0.9398)
			(end 0.508 0.9398)
			(stroke
				(width 0.1524)
				(type default)
			)
			(layer "B.SilkS")
		)
		(fp_rect
			(start 0.508 0.9398)
			(end -0.508 -0.9398)
			(stroke
				(width 0)
				(type default)
			)
			(fill no)
			(layer "B.CrtYd")
		)
		(fp_rect
			(start 0.508 0.9398)
			(end -0.508 -0.9398)
			(stroke
				(width 0)
				(type default)
			)
			(fill no)
			(layer "B.Fab")
		)
		(pad "1" smd custom
			(at 0 -0.4445 90)
			(size 0.1397 0.1397)
			(layers "B.Cu" "B.Mask" "B.Paste")
			(net "SAS_FAULT_LED2")
			(options
				(clearance outline)
				(anchor circle)
			)
			(primitives
				(gr_poly
					(pts
						(arc
							(start -0.1778 0.2794)
							(mid -0.249642 0.249642)
							(end -0.2794 0.1778)
						)
						(arc
							(start -0.2794 -0.1778)
							(mid -0.249642 -0.249642)
							(end -0.1778 -0.2794)
						)
						(arc
							(start 0.1778 -0.2794)
							(mid 0.249642 -0.249642)
							(end 0.2794 -0.1778)
						)
						(arc
							(start 0.2794 0.1778)
							(mid 0.249642 0.249642)
							(end 0.1778 0.2794)
						)
					)
					(width 0)
					(fill yes)
				)
			)
		)
		(pad "2" smd custom
			(at 0 0.4445 90)
			(size 0.1397 0.1397)
			(layers "B.Cu" "B.Mask" "B.Paste")
			(net "SAS_HDD_LED_2")
			(options
				(clearance outline)
				(anchor circle)
			)
			(primitives
				(gr_poly
					(pts
						(arc
							(start -0.1778 0.2794)
							(mid -0.249642 0.249642)
							(end -0.2794 0.1778)
						)
						(arc
							(start -0.2794 -0.1778)
							(mid -0.249642 -0.249642)
							(end -0.1778 -0.2794)
						)
						(arc
							(start 0.1778 -0.2794)
							(mid 0.249642 -0.249642)
							(end 0.2794 -0.1778)
						)
						(arc
							(start 0.2794 0.1778)
							(mid 0.249642 0.249642)
							(end 0.1778 0.2794)
						)
					)
					(width 0)
					(fill yes)
				)
			)
		)
	)
	(footprint ""
		(layer "B.Cu")
		(at 158.42996 -108.356654 90)
		(property "Reference" "SC1244"
			(at 0 0 90)
			(layer "B.SilkS")
			(hide yes)
			(effects
				(font
					(size 1.27 1.27)
				)
				(justify mirror)
			)
		)
		(property "Value" "SCD1U6D3V1KX-GP"
			(at 2.8321 -1.7399 90)
			(unlocked yes)
			(layer "B.Fab")
			(hide yes)
			(effects
				(font
					(size 1.016 1.016)
					(thickness 0.1524)
				)
				(justify mirror)
			)
		)
		(property "Device Type" "C0201H13"
			(at 2.8321 -3.2639 90)
			(unlocked yes)
			(layer "B.Fab")
			(hide yes)
			(effects
				(font
					(size 1.016 1.016)
					(thickness 0.1524)
				)
				(justify mirror)
			)
		)
		(duplicate_pad_numbers_are_jumpers no)
		(fp_rect
			(start 0.2794 0.6477)
			(end -0.2794 -0.6477)
			(stroke
				(width 0)
				(type default)
			)
			(fill no)
			(layer "B.CrtYd")
		)
		(fp_rect
			(start 0.2794 0.6477)
			(end -0.2794 -0.6477)
			(stroke
				(width 0)
				(type default)
			)
			(fill no)
			(layer "B.Fab")
		)
		(pad "1" smd custom
			(at 0 -0.2794 270)
			(size 0.0762 0.0762)
			(layers "B.Cu" "B.Mask" "B.Paste")
			(net "P0V9_E")
			(options
				(clearance outline)
				(anchor circle)
			)
			(primitives
				(gr_poly
					(pts
						(arc
							(start 0.1524 0.127)
							(mid 0.137521 0.162921)
							(end 0.1016 0.1778)
						)
						(arc
							(start -0.1016 0.1778)
							(mid -0.137521 0.162921)
							(end -0.1524 0.127)
						)
						(arc
							(start -0.1524 -0.127)
							(mid -0.137521 -0.162921)
							(end -0.1016 -0.1778)
						)
						(arc
							(start 0.1016 -0.1778)
							(mid 0.137521 -0.162921)
							(end 0.1524 -0.127)
						)
					)
					(width 0)
					(fill yes)
				)
			)
		)
		(pad "2" smd custom
			(at 0 0.2794 270)
			(size 0.0762 0.0762)
			(layers "B.Cu" "B.Mask" "B.Paste")
			(net "GND")
			(options
				(clearance outline)
				(anchor circle)
			)
			(primitives
				(gr_poly
					(pts
						(arc
							(start 0.1524 0.127)
							(mid 0.137521 0.162921)
							(end 0.1016 0.1778)
						)
						(arc
							(start -0.1016 0.1778)
							(mid -0.137521 0.162921)
							(end -0.1524 0.127)
						)
						(arc
							(start -0.1524 -0.127)
							(mid -0.137521 -0.162921)
							(end -0.1016 -0.1778)
						)
						(arc
							(start 0.1016 -0.1778)
							(mid 0.137521 -0.162921)
							(end 0.1524 -0.127)
						)
					)
					(width 0)
					(fill yes)
				)
			)
		)
	)
)
